(kicad_pcb
	(version 20241229)
	(generator "pcbnew")
	(generator_version "9.0")
	(general
		(thickness 1.599998)
		(legacy_teardrops no)
	)
	(paper "A4")
	(title_block
		(date "2023-02-12")
		(rev "1.1.5")
		(comment 9 "footprints 179-184 of 473")
	)
	(layers
		(0 "F.Cu" signal)
		(4 "In1.Cu" power "In1.GND")
		(6 "In2.Cu" signal)
		(8 "In3.Cu" power "In3.GND")
		(10 "In4.Cu" power "In4.VCC")
		(12 "In5.Cu" signal)
		(14 "In6.Cu" power "In6.VCC")
		(2 "B.Cu" signal)
		(9 "F.Adhes" user "F.Adhesive")
		(11 "B.Adhes" user "B.Adhesive")
		(13 "F.Paste" user)
		(15 "B.Paste" user)
		(5 "F.SilkS" user "F.Silkscreen")
		(7 "B.SilkS" user "B.Silkscreen")
		(1 "F.Mask" user)
		(3 "B.Mask" user)
		(17 "Dwgs.User" user "User.Drawings")
		(19 "Cmts.User" user "User.Comments")
		(21 "Eco1.User" user "User.Eco1")
		(23 "Eco2.User" user "User.Eco2")
		(25 "Edge.Cuts" user)
		(27 "Margin" user)
		(31 "F.CrtYd" user "F.Courtyard")
		(29 "B.CrtYd" user "B.Courtyard")
		(35 "F.Fab" user)
		(33 "B.Fab" user)
	)
	(footprint "lpddr4-test-board-footprints:mounting-hole-3.2mm"
		(layer "F.Cu")
		(at 213.9 49.1)
		(property "Reference" "MH2"
			(at -0.178 4.025 0)
			(layer "F.SilkS")
			(hide yes)
			(effects
				(font
					(size 0.7 0.7)
					(thickness 0.15)
				)
				(justify left bottom)
			)
		)
		(property "Value" "M3.2"
			(at -0.153 -4.153 0)
			(layer "F.Fab")
			(hide yes)
			(effects
				(font
					(size 0.7 0.7)
					(thickness 0.15)
				)
				(justify left bottom)
			)
		)
		(attr through_hole board_only exclude_from_bom)
		(pad "1" thru_hole circle
			(at 0 0)
			(size 6 6)
			(drill 3.2)
			(layers "*.Cu" "*.Mask")
			(remove_unused_layers no)
		)
	)
	(footprint "antmicro-footprints:R_0805_2012Metric"
		(layer "F.Cu")
		(at 131.9 68.1)
		(property "Reference" "R99"
			(at -1.1 -1 0)
			(layer "F.SilkS")
			(effects
				(font
					(size 0.7 0.7)
					(thickness 0.15)
				)
				(justify left bottom)
			)
		)
		(property "Value" "R_0R_0805"
			(at 0 1.8 0)
			(layer "F.Fab")
			(effects
				(font
					(size 0.7 0.7)
					(thickness 0.15)
				)
				(justify left bottom)
			)
		)
		(property "Description" "0R resistor in 0805 package with unspecified tolerance"
			(at 0 0 0)
			(layer "F.Fab")
			(hide yes)
			(effects
				(font
					(size 1.27 1.27)
					(thickness 0.15)
				)
			)
		)
		(property "Author" "Antmicro"
			(at 0 0 0)
			(layer "F.Fab")
			(hide yes)
			(effects
				(font
					(size 1 1)
					(thickness 0.15)
				)
			)
		)
		(property "Current" "2.5A"
			(at 0 0 0)
			(layer "F.Fab")
			(hide yes)
			(effects
				(font
					(size 1 1)
					(thickness 0.15)
				)
			)
		)
		(property "License" "Apache-2.0"
			(at 0 0 0)
			(layer "F.Fab")
			(hide yes)
			(effects
				(font
					(size 1 1)
					(thickness 0.15)
				)
			)
		)
		(property "MPN" "CRCW08050000Z0EA"
			(at 0 0 0)
			(layer "F.Fab")
			(hide yes)
			(effects
				(font
					(size 1 1)
					(thickness 0.15)
				)
			)
		)
		(property "Manufacturer" "Vishay"
			(at 0 0 0)
			(layer "F.Fab")
			(hide yes)
			(effects
				(font
					(size 1 1)
					(thickness 0.15)
				)
			)
		)
		(property "Tolerance" ""
			(at 0 0 0)
			(layer "F.Fab")
			(hide yes)
			(effects
				(font
					(size 1 1)
					(thickness 0.15)
				)
			)
		)
		(property "Val" "0R"
			(at 0 0 0)
			(layer "F.Fab")
			(hide yes)
			(effects
				(font
					(size 1 1)
					(thickness 0.15)
				)
			)
		)
		(sheetname "Supply")
		(sheetfile "supply.kicad_sch")
		(attr exclude_from_pos_files exclude_from_bom dnp)
		(fp_line
			(start -0.32 0.699)
			(end 0.28 0.699)
			(stroke
				(width 0.15)
				(type solid)
			)
			(layer "F.SilkS")
		)
		(fp_line
			(start -0.3 -0.701)
			(end 0.298 -0.701)
			(stroke
				(width 0.15)
				(type solid)
			)
			(layer "F.SilkS")
		)
		(fp_rect
			(start -1.75 -0.85)
			(end 1.75 0.85)
			(stroke
				(width 0.05)
				(type solid)
			)
			(fill no)
			(layer "F.CrtYd")
		)
		(fp_line
			(start -0.951 -0.682)
			(end 0.949 -0.682)
			(stroke
				(width 0.15)
				(type solid)
			)
			(layer "F.Fab")
		)
		(fp_line
			(start -0.951 -0.677)
			(end -0.951 0.675)
			(stroke
				(width 0.15)
				(type solid)
			)
			(layer "F.Fab")
		)
		(fp_line
			(start -0.951 0.68)
			(end 0.949 0.68)
			(stroke
				(width 0.15)
				(type solid)
			)
			(layer "F.Fab")
		)
		(fp_line
			(start 0.949 -0.677)
			(end 0.949 0.675)
			(stroke
				(width 0.15)
				(type solid)
			)
			(layer "F.Fab")
		)
		(pad "1" smd roundrect
			(at -1.1 -0.001)
			(size 1 1.4)
			(layers "F.Cu" "F.Mask" "F.Paste")
			(roundrect_rratio 0.15)
			(net 551 "/Supply/VDD1V8")
			(pintype "passive")
		)
		(pad "2" smd roundrect
			(at 1.1 -0.001)
			(size 1 1.4)
			(layers "F.Cu" "F.Mask" "F.Paste")
			(roundrect_rratio 0.15)
			(net 460 "1V8_SYS")
			(pintype "passive")
		)
	)
	(footprint "antmicro-footprints:C_0402_1005Metric"
		(layer "F.Cu")
		(at 123.4325 97.249 180)
		(descr "Capacitor SMD 0402")
		(tags "capacitor SMD 0402")
		(property "Reference" "C171"
			(at 1.9325 2.449 180)
			(layer "F.SilkS")
			(effects
				(font
					(size 0.7 0.7)
					(thickness 0.15)
				)
				(justify left bottom)
			)
		)
		(property "Value" "C_22u_0402"
			(at 0 1.4 180)
			(layer "F.Fab")
			(effects
				(font
					(size 0.7 0.7)
					(thickness 0.15)
				)
				(justify left bottom)
			)
		)
		(property "Description" " "
			(at 0 0 180)
			(layer "F.Fab")
			(hide yes)
			(effects
				(font
					(size 1.27 1.27)
					(thickness 0.15)
				)
			)
		)
		(property "Author" "Antmicro"
			(at 246.865 194.498 0)
			(layer "F.Fab")
			(hide yes)
			(effects
				(font
					(size 1 1)
					(thickness 0.15)
				)
			)
		)
		(property "Dielectric" ""
			(at 246.865 194.498 0)
			(layer "F.Fab")
			(hide yes)
			(effects
				(font
					(size 1 1)
					(thickness 0.15)
				)
			)
		)
		(property "License" "Apache-2.0"
			(at 246.865 194.498 0)
			(layer "F.Fab")
			(hide yes)
			(effects
				(font
					(size 1 1)
					(thickness 0.15)
				)
			)
		)
		(property "MPN" "04024W226MAT2A"
			(at 246.865 194.498 0)
			(layer "F.Fab")
			(hide yes)
			(effects
				(font
					(size 1 1)
					(thickness 0.15)
				)
			)
		)
		(property "Manufacturer" "AVX"
			(at 246.865 194.498 0)
			(layer "F.Fab")
			(hide yes)
			(effects
				(font
					(size 1 1)
					(thickness 0.15)
				)
			)
		)
		(property "Val" "22u"
			(at 246.865 194.498 0)
			(layer "F.Fab")
			(hide yes)
			(effects
				(font
					(size 1 1)
					(thickness 0.15)
				)
			)
		)
		(property "Voltage" ""
			(at 246.865 194.498 0)
			(layer "F.Fab")
			(hide yes)
			(effects
				(font
					(size 1 1)
					(thickness 0.15)
				)
			)
		)
		(sheetname "Supply")
		(sheetfile "supply.kicad_sch")
		(attr smd)
		(fp_rect
			(start -0.94 -0.47)
			(end 0.94 0.47)
			(stroke
				(width 0.05)
				(type solid)
			)
			(fill no)
			(layer "F.CrtYd")
		)
		(fp_rect
			(start -0.499 -0.249)
			(end 0.499 0.249)
			(stroke
				(width 0.15)
				(type solid)
			)
			(fill no)
			(layer "F.Fab")
		)
		(pad "1" smd roundrect
			(at -0.484 0 180)
			(size 0.59 0.64)
			(layers "F.Cu" "F.Mask" "F.Paste")
			(roundrect_rratio 0.25)
			(net 588 "/Supply/1V0_REG")
			(pintype "passive")
		)
		(pad "2" smd roundrect
			(at 0.484 0 180)
			(size 0.59 0.64)
			(layers "F.Cu" "F.Mask" "F.Paste")
			(roundrect_rratio 0.25)
			(net 5 "GND")
			(pintype "passive")
		)
	)
	(footprint "antmicro-footprints:C_0402_1005Metric"
		(layer "F.Cu")
		(at 124.05 52.475 90)
		(descr "Capacitor SMD 0402")
		(tags "capacitor SMD 0402")
		(property "Reference" "C192"
			(at 0.775 0.35 90)
			(layer "F.SilkS")
			(effects
				(font
					(size 0.7 0.7)
					(thickness 0.15)
				)
				(justify left bottom)
			)
		)
		(property "Value" "C_470n_0402"
			(at 0 1.4 90)
			(layer "F.Fab")
			(effects
				(font
					(size 0.7 0.7)
					(thickness 0.15)
				)
				(justify left bottom)
			)
		)
		(property "Description" " "
			(at 0 0 90)
			(layer "F.Fab")
			(hide yes)
			(effects
				(font
					(size 1.27 1.27)
					(thickness 0.15)
				)
			)
		)
		(property "Author" "Antmicro"
			(at 176.525 -71.575 0)
			(layer "F.Fab")
			(hide yes)
			(effects
				(font
					(size 1 1)
					(thickness 0.15)
				)
			)
		)
		(property "Dielectric" ""
			(at 176.525 -71.575 0)
			(layer "F.Fab")
			(hide yes)
			(effects
				(font
					(size 1 1)
					(thickness 0.15)
				)
			)
		)
		(property "License" "Apache-2.0"
			(at 176.525 -71.575 0)
			(layer "F.Fab")
			(hide yes)
			(effects
				(font
					(size 1 1)
					(thickness 0.15)
				)
			)
		)
		(property "MPN" "C1005X5R1E474M050BB"
			(at 176.525 -71.575 0)
			(layer "F.Fab")
			(hide yes)
			(effects
				(font
					(size 1 1)
					(thickness 0.15)
				)
			)
		)
		(property "Manufacturer" "TDK"
			(at 176.525 -71.575 0)
			(layer "F.Fab")
			(hide yes)
			(effects
				(font
					(size 1 1)
					(thickness 0.15)
				)
			)
		)
		(property "Val" "470n"
			(at 176.525 -71.575 0)
			(layer "F.Fab")
			(hide yes)
			(effects
				(font
					(size 1 1)
					(thickness 0.15)
				)
			)
		)
		(property "Voltage" ""
			(at 176.525 -71.575 0)
			(layer "F.Fab")
			(hide yes)
			(effects
				(font
					(size 1 1)
					(thickness 0.15)
				)
			)
		)
		(sheetname "Supply")
		(sheetfile "supply.kicad_sch")
		(attr exclude_from_pos_files exclude_from_bom dnp)
		(fp_rect
			(start -0.94 -0.47)
			(end 0.94 0.47)
			(stroke
				(width 0.05)
				(type solid)
			)
			(fill no)
			(layer "F.CrtYd")
		)
		(fp_rect
			(start -0.499 -0.249)
			(end 0.499 0.249)
			(stroke
				(width 0.15)
				(type solid)
			)
			(fill no)
			(layer "F.Fab")
		)
		(pad "1" smd roundrect
			(at -0.484 0 90)
			(size 0.59 0.64)
			(layers "F.Cu" "F.Mask" "F.Paste")
			(roundrect_rratio 0.25)
			(net 626 "/Supply/VDDQ_REF")
			(pintype "passive")
		)
		(pad "2" smd roundrect
			(at 0.484 0 90)
			(size 0.59 0.64)
			(layers "F.Cu" "F.Mask" "F.Paste")
			(roundrect_rratio 0.25)
			(net 5 "GND")
			(pintype "passive")
		)
	)
	(footprint "antmicro-footprints:R_0805_2012Metric"
		(layer "F.Cu")
		(at 122.1492 108.7)
		(property "Reference" "R111"
			(at 1.6508 0.4 0)
			(layer "F.SilkS")
			(effects
				(font
					(size 0.7 0.7)
					(thickness 0.15)
				)
				(justify left bottom)
			)
		)
		(property "Value" "R_0R_0805"
			(at 0 1.8 0)
			(layer "F.Fab")
			(effects
				(font
					(size 0.7 0.7)
					(thickness 0.15)
				)
				(justify left bottom)
			)
		)
		(property "Description" "0R resistor in 0805 package with unspecified tolerance"
			(at 0 0 0)
			(layer "F.Fab")
			(hide yes)
			(effects
				(font
					(size 1.27 1.27)
					(thickness 0.15)
				)
			)
		)
		(property "Author" "Antmicro"
			(at 0 0 0)
			(layer "F.Fab")
			(hide yes)
			(effects
				(font
					(size 1 1)
					(thickness 0.15)
				)
			)
		)
		(property "Current" "2.5A"
			(at 0 0 0)
			(layer "F.Fab")
			(hide yes)
			(effects
				(font
					(size 1 1)
					(thickness 0.15)
				)
			)
		)
		(property "License" "Apache-2.0"
			(at 0 0 0)
			(layer "F.Fab")
			(hide yes)
			(effects
				(font
					(size 1 1)
					(thickness 0.15)
				)
			)
		)
		(property "MPN" "CRCW08050000Z0EA"
			(at 0 0 0)
			(layer "F.Fab")
			(hide yes)
			(effects
				(font
					(size 1 1)
					(thickness 0.15)
				)
			)
		)
		(property "Manufacturer" "Vishay"
			(at 0 0 0)
			(layer "F.Fab")
			(hide yes)
			(effects
				(font
					(size 1 1)
					(thickness 0.15)
				)
			)
		)
		(property "Tolerance" ""
			(at 0 0 0)
			(layer "F.Fab")
			(hide yes)
			(effects
				(font
					(size 1 1)
					(thickness 0.15)
				)
			)
		)
		(property "Val" "0R"
			(at 0 0 0)
			(layer "F.Fab")
			(hide yes)
			(effects
				(font
					(size 1 1)
					(thickness 0.15)
				)
			)
		)
		(sheetname "Supply")
		(sheetfile "supply.kicad_sch")
		(attr smd)
		(fp_line
			(start -0.32 0.699)
			(end 0.28 0.699)
			(stroke
				(width 0.15)
				(type solid)
			)
			(layer "F.SilkS")
		)
		(fp_line
			(start -0.3 -0.701)
			(end 0.298 -0.701)
			(stroke
				(width 0.15)
				(type solid)
			)
			(layer "F.SilkS")
		)
		(fp_rect
			(start -1.75 -0.85)
			(end 1.75 0.85)
			(stroke
				(width 0.05)
				(type solid)
			)
			(fill no)
			(layer "F.CrtYd")
		)
		(fp_line
			(start -0.951 -0.682)
			(end 0.949 -0.682)
			(stroke
				(width 0.15)
				(type solid)
			)
			(layer "F.Fab")
		)
		(fp_line
			(start -0.951 -0.677)
			(end -0.951 0.675)
			(stroke
				(width 0.15)
				(type solid)
			)
			(layer "F.Fab")
		)
		(fp_line
			(start -0.951 0.68)
			(end 0.949 0.68)
			(stroke
				(width 0.15)
				(type solid)
			)
			(layer "F.Fab")
		)
		(fp_line
			(start 0.949 -0.677)
			(end 0.949 0.675)
			(stroke
				(width 0.15)
				(type solid)
			)
			(layer "F.Fab")
		)
		(pad "1" smd roundrect
			(at -1.1 -0.001)
			(size 1 1.4)
			(layers "F.Cu" "F.Mask" "F.Paste")
			(roundrect_rratio 0.15)
			(net 55 "Net-(C141-Pad1)")
			(pintype "passive")
		)
		(pad "2" smd roundrect
			(at 1.1 -0.001)
			(size 1 1.4)
			(layers "F.Cu" "F.Mask" "F.Paste")
			(roundrect_rratio 0.15)
			(net 463 "VCC5V0_INT")
			(pintype "passive")
		)
	)
	(footprint "antmicro-footprints:R_0402_1005Metric"
		(layer "F.Cu")
		(at 140.1825 87.099)
		(descr "Resistor SMD 0402")
		(tags "resistor SMD 0402")
		(property "Reference" "R112"
			(at -3.6825 -0.799 0)
			(layer "F.SilkS")
			(effects
				(font
					(size 0.7 0.7)
					(thickness 0.15)
				)
				(justify left bottom)
			)
		)
		(property "Value" "R_330R_0402"
			(at 0 1.4 0)
			(layer "F.Fab")
			(effects
				(font
					(size 0.7 0.7)
					(thickness 0.15)
				)
				(justify left bottom)
			)
		)
		(property "Description" "330R resistor in 0402 package with 1% tolerance"
			(at 0 0 0)
			(layer "F.Fab")
			(hide yes)
			(effects
				(font
					(size 1.27 1.27)
					(thickness 0.15)
				)
			)
		)
		(property "Author" "Antmicro"
			(at 0 0 0)
			(layer "F.Fab")
			(hide yes)
			(effects
				(font
					(size 1 1)
					(thickness 0.15)
				)
			)
		)
		(property "License" "Apache-2.0"
			(at 0 0 0)
			(layer "F.Fab")
			(hide yes)
			(effects
				(font
					(size 1 1)
					(thickness 0.15)
				)
			)
		)
		(property "MPN" "CR0402-FX-3300GLF"
			(at 0 0 0)
			(layer "F.Fab")
			(hide yes)
			(effects
				(font
					(size 1 1)
					(thickness 0.15)
				)
			)
		)
		(property "Manufacturer" "Bourns"
			(at 0 0 0)
			(layer "F.Fab")
			(hide yes)
			(effects
				(font
					(size 1 1)
					(thickness 0.15)
				)
			)
		)
		(property "Tolerance" "1%"
			(at 0 0 0)
			(layer "F.Fab")
			(hide yes)
			(effects
				(font
					(size 1 1)
					(thickness 0.15)
				)
			)
		)
		(property "Val" "330R"
			(at 0 0 0)
			(layer "F.Fab")
			(hide yes)
			(effects
				(font
					(size 1 1)
					(thickness 0.15)
				)
			)
		)
		(sheetname "Supply")
		(sheetfile "supply.kicad_sch")
		(attr smd)
		(fp_rect
			(start -0.93 -0.47)
			(end 0.93 0.47)
			(stroke
				(width 0.05)
				(type solid)
			)
			(fill no)
			(layer "F.CrtYd")
		)
		(fp_rect
			(start -0.5 -0.25)
			(end 0.5 0.25)
			(stroke
				(width 0.15)
				(type solid)
			)
			(fill no)
			(layer "F.Fab")
		)
		(pad "1" smd roundrect
			(at -0.485 0)
			(size 0.59 0.64)
			(layers "F.Cu" "F.Mask" "F.Paste")
			(roundrect_rratio 0.25)
			(net 556 "Net-(PWR4-Pad2)")
			(pintype "passive")
		)
		(pad "2" smd roundrect
			(at 0.485 0)
			(size 0.59 0.64)
			(layers "F.Cu" "F.Mask" "F.Paste")
			(roundrect_rratio 0.25)
			(net 236 "Net-(Q10-D)")
			(pintype "passive")
		)
	)
)
